(kicad_pcb
	(version 20260206)
	(generator "pcbnew")
	(generator_version "10.0")
	(general
		(thickness 1.6)
		(legacy_teardrops no)
	)
	(paper "A4")
	(title_block
		(title "03242023_DA0F0TMBIJ0_F0T_Motherboard_J_brd_V01_OCP.brd")
		(comment 1 "Grand Teton / footprints 5743-5749 of 6105")
	)
	(layers
		(0 "F.Cu" signal "TOP")
		(4 "In1.Cu" signal "GND")
		(6 "In2.Cu" signal "IN1")
		(8 "In3.Cu" signal "GND1")
		(10 "In4.Cu" signal "IN2")
		(12 "In5.Cu" signal "GND2")
		(14 "In6.Cu" signal "IN3")
		(16 "In7.Cu" signal "GND3")
		(18 "In8.Cu" signal "VCC")
		(20 "In9.Cu" signal "VCC1")
		(22 "In10.Cu" signal "GND4")
		(24 "In11.Cu" signal "IN4")
		(26 "In12.Cu" signal "GND5")
		(28 "In13.Cu" signal "IN5")
		(30 "In14.Cu" signal "GND6")
		(32 "In15.Cu" signal "IN6")
		(34 "In16.Cu" signal "GND7")
		(2 "B.Cu" signal "BOTTOM")
		(9 "F.Adhes" user "F.Adhesive")
		(11 "B.Adhes" user "B.Adhesive")
		(13 "F.Paste" user "Package Geometry/Pastemask Top")
		(15 "B.Paste" user "Package Geometry/Pastemask Bottom")
		(5 "F.SilkS" user "Ref Des/Silkscreen Top")
		(7 "B.SilkS" user "Ref Des/Silkscreen Bottom")
		(1 "F.Mask" user "Board Geometry/Soldermask Top")
		(3 "B.Mask" user "Board Geometry/Soldermask Bottom")
		(17 "Dwgs.User" user "User.Drawings")
		(19 "Cmts.User" user "User.Comments")
		(21 "Eco1.User" user "User.Eco1")
		(23 "Eco2.User" user "User.Eco2")
		(25 "Edge.Cuts" user "Board Geometry/Outline")
		(27 "Margin" user)
		(31 "F.CrtYd" user "Package Geometry/Place Bound Top")
		(29 "B.CrtYd" user "Package Geometry/Place Bound Bottom")
		(35 "F.Fab" user "Ref Des/Assembly Top")
		(33 "B.Fab" user "Ref Des/Assembly Bottom")
	)
	(footprint ""
		(layer "B.Cu")
		(at 254.824484 -106.467148)
		(property "Reference" "R1204"
			(at 0 0 0)
			(layer "B.SilkS")
			(hide yes)
			(effects
				(font
					(size 1.27 1.27)
				)
				(justify mirror)
			)
		)
		(property "Value" ""
			(at 0 0 0)
			(layer "B.Fab")
			(effects
				(font
					(size 1.27 1.27)
				)
				(justify mirror)
			)
		)
		(duplicate_pad_numbers_are_jumpers no)
		(fp_line
			(start -0.7874 -0.4064)
			(end -0.7874 0.4064)
			(stroke
				(width 0.1524)
				(type default)
			)
			(layer "B.SilkS")
		)
		(fp_line
			(start -0.7874 0.4064)
			(end 0.7874 0.4064)
			(stroke
				(width 0.1524)
				(type default)
			)
			(layer "B.SilkS")
		)
		(fp_line
			(start 0.7874 -0.4064)
			(end -0.7874 -0.4064)
			(stroke
				(width 0.1524)
				(type default)
			)
			(layer "B.SilkS")
		)
		(fp_line
			(start 0.7874 0.4064)
			(end 0.7874 -0.4064)
			(stroke
				(width 0.1524)
				(type default)
			)
			(layer "B.SilkS")
		)
		(fp_line
			(start -0.67945 -0.3048)
			(end -0.67945 0.3048)
			(stroke
				(width 0.1)
				(type default)
			)
			(layer "B.Fab")
		)
		(fp_line
			(start -0.67945 0.3048)
			(end -0.120396 0.3048)
			(stroke
				(width 0.1)
				(type default)
			)
			(layer "B.Fab")
		)
		(fp_line
			(start -0.12065 -0.3048)
			(end -0.67945 -0.3048)
			(stroke
				(width 0.1)
				(type default)
			)
			(layer "B.Fab")
		)
		(fp_line
			(start -0.12065 -0.2794)
			(end -0.12065 -0.3048)
			(stroke
				(width 0.1)
				(type default)
			)
			(layer "B.Fab")
		)
		(fp_line
			(start -0.120396 0.2794)
			(end 0.12065 0.2794)
			(stroke
				(width 0.1)
				(type default)
			)
			(layer "B.Fab")
		)
		(fp_line
			(start -0.120396 0.3048)
			(end -0.120396 0.2794)
			(stroke
				(width 0.1)
				(type default)
			)
			(layer "B.Fab")
		)
		(fp_line
			(start 0.12065 -0.305054)
			(end 0.12065 -0.2794)
			(stroke
				(width 0.1)
				(type default)
			)
			(layer "B.Fab")
		)
		(fp_line
			(start 0.12065 -0.2794)
			(end -0.12065 -0.2794)
			(stroke
				(width 0.1)
				(type default)
			)
			(layer "B.Fab")
		)
		(fp_line
			(start 0.12065 0.2794)
			(end 0.12065 0.3048)
			(stroke
				(width 0.1)
				(type default)
			)
			(layer "B.Fab")
		)
		(fp_line
			(start 0.12065 0.3048)
			(end 0.67945 0.3048)
			(stroke
				(width 0.1)
				(type default)
			)
			(layer "B.Fab")
		)
		(fp_line
			(start 0.67945 -0.305054)
			(end 0.12065 -0.305054)
			(stroke
				(width 0.1)
				(type default)
			)
			(layer "B.Fab")
		)
		(fp_line
			(start 0.67945 0.3048)
			(end 0.67945 -0.305054)
			(stroke
				(width 0.1)
				(type default)
			)
			(layer "B.Fab")
		)
		(pad "1" smd circle
			(at 0.40005 0 180)
			(size 0 0)
			(layers "B.Cu" "B.Mask" "B.Paste")
			(net "P3V3_AUX")
		)
		(pad "2" smd circle
			(at -0.40005 0 180)
			(size 0 0)
			(layers "B.Cu" "B.Mask" "B.Paste")
			(net "PU_CK440_SHFT_LD_N")
		)
	)
	(footprint ""
		(layer "B.Cu")
		(at 410.851604 -250.791218 90)
		(property "Reference" "C506"
			(at 0 0 90)
			(layer "B.SilkS")
			(hide yes)
			(effects
				(font
					(size 1.27 1.27)
				)
				(justify mirror)
			)
		)
		(property "Value" ""
			(at 0 0 90)
			(layer "B.Fab")
			(effects
				(font
					(size 1.27 1.27)
				)
				(justify mirror)
			)
		)
		(duplicate_pad_numbers_are_jumpers no)
		(fp_line
			(start 1.524 -0.762)
			(end -1.524 -0.762)
			(stroke
				(width 0.1524)
				(type default)
			)
			(layer "B.SilkS")
		)
		(fp_line
			(start -1.524 -0.762)
			(end -1.524 0.762)
			(stroke
				(width 0.1524)
				(type default)
			)
			(layer "B.SilkS")
		)
		(fp_line
			(start 1.524 0.762)
			(end 1.524 -0.762)
			(stroke
				(width 0.1524)
				(type default)
			)
			(layer "B.SilkS")
		)
		(fp_line
			(start -1.524 0.762)
			(end 1.524 0.762)
			(stroke
				(width 0.1524)
				(type default)
			)
			(layer "B.SilkS")
		)
		(fp_line
			(start 1.1049 -0.724916)
			(end 1.1049 0.724916)
			(stroke
				(width 0.1)
				(type default)
			)
			(layer "B.Fab")
		)
		(fp_line
			(start -1.1049 -0.724916)
			(end 1.1049 -0.724916)
			(stroke
				(width 0.1)
				(type default)
			)
			(layer "B.Fab")
		)
		(fp_line
			(start 1.1049 0.724916)
			(end -1.1049 0.724916)
			(stroke
				(width 0.1)
				(type default)
			)
			(layer "B.Fab")
		)
		(fp_line
			(start -1.1049 0.724916)
			(end -1.1049 -0.724916)
			(stroke
				(width 0.1)
				(type default)
			)
			(layer "B.Fab")
		)
		(pad "1" smd rect
			(at 0.889 0 90)
			(size 1.016 1.27)
			(layers "B.Cu" "B.Mask" "B.Paste")
			(net "PVCCFA_EHV_FIVRA_CPU0")
		)
		(pad "2" smd rect
			(at -0.889 0 90)
			(size 1.016 1.27)
			(layers "B.Cu" "B.Mask" "B.Paste")
			(net "GND")
		)
	)
	(footprint ""
		(layer "B.Cu")
		(at 21.914612 -168.437814 180)
		(property "Reference" "R2576"
			(at 0 0 0)
			(layer "B.SilkS")
			(hide yes)
			(effects
				(font
					(size 1.27 1.27)
				)
				(justify mirror)
			)
		)
		(property "Value" ""
			(at 0 0 0)
			(layer "B.Fab")
			(effects
				(font
					(size 1.27 1.27)
				)
				(justify mirror)
			)
		)
		(duplicate_pad_numbers_are_jumpers no)
		(fp_line
			(start 0.7874 0.4064)
			(end 0.7874 -0.4064)
			(stroke
				(width 0.1524)
				(type default)
			)
			(layer "B.SilkS")
		)
		(fp_line
			(start 0.7874 -0.4064)
			(end -0.7874 -0.4064)
			(stroke
				(width 0.1524)
				(type default)
			)
			(layer "B.SilkS")
		)
		(fp_line
			(start -0.7874 0.4064)
			(end 0.7874 0.4064)
			(stroke
				(width 0.1524)
				(type default)
			)
			(layer "B.SilkS")
		)
		(fp_line
			(start -0.7874 -0.4064)
			(end -0.7874 0.4064)
			(stroke
				(width 0.1524)
				(type default)
			)
			(layer "B.SilkS")
		)
		(fp_line
			(start 0.67945 0.3048)
			(end 0.67945 -0.305054)
			(stroke
				(width 0.1)
				(type default)
			)
			(layer "B.Fab")
		)
		(fp_line
			(start 0.67945 -0.305054)
			(end 0.12065 -0.305054)
			(stroke
				(width 0.1)
				(type default)
			)
			(layer "B.Fab")
		)
		(fp_line
			(start 0.12065 0.3048)
			(end 0.67945 0.3048)
			(stroke
				(width 0.1)
				(type default)
			)
			(layer "B.Fab")
		)
		(fp_line
			(start 0.12065 0.2794)
			(end 0.12065 0.3048)
			(stroke
				(width 0.1)
				(type default)
			)
			(layer "B.Fab")
		)
		(fp_line
			(start 0.12065 -0.2794)
			(end -0.12065 -0.2794)
			(stroke
				(width 0.1)
				(type default)
			)
			(layer "B.Fab")
		)
		(fp_line
			(start 0.12065 -0.305054)
			(end 0.12065 -0.2794)
			(stroke
				(width 0.1)
				(type default)
			)
			(layer "B.Fab")
		)
		(fp_line
			(start -0.120396 0.3048)
			(end -0.120396 0.2794)
			(stroke
				(width 0.1)
				(type default)
			)
			(layer "B.Fab")
		)
		(fp_line
			(start -0.120396 0.2794)
			(end 0.12065 0.2794)
			(stroke
				(width 0.1)
				(type default)
			)
			(layer "B.Fab")
		)
		(fp_line
			(start -0.12065 -0.2794)
			(end -0.12065 -0.3048)
			(stroke
				(width 0.1)
				(type default)
			)
			(layer "B.Fab")
		)
		(fp_line
			(start -0.12065 -0.3048)
			(end -0.67945 -0.3048)
			(stroke
				(width 0.1)
				(type default)
			)
			(layer "B.Fab")
		)
		(fp_line
			(start -0.67945 0.3048)
			(end -0.120396 0.3048)
			(stroke
				(width 0.1)
				(type default)
			)
			(layer "B.Fab")
		)
		(fp_line
			(start -0.67945 -0.3048)
			(end -0.67945 0.3048)
			(stroke
				(width 0.1)
				(type default)
			)
			(layer "B.Fab")
		)
		(pad "1" smd circle
			(at 0.40005 0)
			(size 0 0)
			(layers "B.Cu" "B.Mask" "B.Paste")
			(net "PWRGD_PVCCD_HV_CPU1")
		)
		(pad "2" smd circle
			(at -0.40005 0)
			(size 0 0)
			(layers "B.Cu" "B.Mask" "B.Paste")
			(net "PWRGD_PVCCD_HV_CPU1_R")
		)
	)
	(footprint ""
		(layer "B.Cu")
		(at 119.866918 -241.12347 90)
		(property "Reference" "C471"
			(at 0 0 90)
			(layer "B.SilkS")
			(hide yes)
			(effects
				(font
					(size 1.27 1.27)
				)
				(justify mirror)
			)
		)
		(property "Value" ""
			(at 0 0 90)
			(layer "B.Fab")
			(effects
				(font
					(size 1.27 1.27)
				)
				(justify mirror)
			)
		)
		(duplicate_pad_numbers_are_jumpers no)
		(fp_line
			(start 1.524 -0.762)
			(end -1.524 -0.762)
			(stroke
				(width 0.1524)
				(type default)
			)
			(layer "B.SilkS")
		)
		(fp_line
			(start -1.524 -0.762)
			(end -1.524 0.762)
			(stroke
				(width 0.1524)
				(type default)
			)
			(layer "B.SilkS")
		)
		(fp_line
			(start 1.524 0.762)
			(end 1.524 -0.762)
			(stroke
				(width 0.1524)
				(type default)
			)
			(layer "B.SilkS")
		)
		(fp_line
			(start -1.524 0.762)
			(end 1.524 0.762)
			(stroke
				(width 0.1524)
				(type default)
			)
			(layer "B.SilkS")
		)
		(fp_line
			(start 1.1049 -0.724916)
			(end 1.1049 0.724916)
			(stroke
				(width 0.1)
				(type default)
			)
			(layer "B.Fab")
		)
		(fp_line
			(start -1.1049 -0.724916)
			(end 1.1049 -0.724916)
			(stroke
				(width 0.1)
				(type default)
			)
			(layer "B.Fab")
		)
		(fp_line
			(start 1.1049 0.724916)
			(end -1.1049 0.724916)
			(stroke
				(width 0.1)
				(type default)
			)
			(layer "B.Fab")
		)
		(fp_line
			(start -1.1049 0.724916)
			(end -1.1049 -0.724916)
			(stroke
				(width 0.1)
				(type default)
			)
			(layer "B.Fab")
		)
		(pad "1" smd rect
			(at 0.889 0 90)
			(size 1.016 1.27)
			(layers "B.Cu" "B.Mask" "B.Paste")
			(net "PVCCD_HV_CPU1")
		)
		(pad "2" smd rect
			(at -0.889 0 90)
			(size 1.016 1.27)
			(layers "B.Cu" "B.Mask" "B.Paste")
			(net "GND")
		)
	)
	(footprint ""
		(layer "B.Cu")
		(at 44.16171 -315.423804 90)
		(property "Reference" "R3894"
			(at 0 0 90)
			(layer "B.SilkS")
			(hide yes)
			(effects
				(font
					(size 1.27 1.27)
				)
				(justify mirror)
			)
		)
		(property "Value" ""
			(at 0 0 90)
			(layer "B.Fab")
			(effects
				(font
					(size 1.27 1.27)
				)
				(justify mirror)
			)
		)
		(duplicate_pad_numbers_are_jumpers no)
		(fp_line
			(start 0.7874 -0.4064)
			(end -0.7874 -0.4064)
			(stroke
				(width 0.1524)
				(type default)
			)
			(layer "B.SilkS")
		)
		(fp_line
			(start -0.7874 -0.4064)
			(end -0.7874 0.4064)
			(stroke
				(width 0.1524)
				(type default)
			)
			(layer "B.SilkS")
		)
		(fp_line
			(start 0.7874 0.4064)
			(end 0.7874 -0.4064)
			(stroke
				(width 0.1524)
				(type default)
			)
			(layer "B.SilkS")
		)
		(fp_line
			(start -0.7874 0.4064)
			(end 0.7874 0.4064)
			(stroke
				(width 0.1524)
				(type default)
			)
			(layer "B.SilkS")
		)
		(fp_line
			(start 0.67945 -0.305054)
			(end 0.12065 -0.305054)
			(stroke
				(width 0.1)
				(type default)
			)
			(layer "B.Fab")
		)
		(fp_line
			(start 0.12065 -0.305054)
			(end 0.12065 -0.2794)
			(stroke
				(width 0.1)
				(type default)
			)
			(layer "B.Fab")
		)
		(fp_line
			(start -0.12065 -0.3048)
			(end -0.67945 -0.3048)
			(stroke
				(width 0.1)
				(type default)
			)
			(layer "B.Fab")
		)
		(fp_line
			(start -0.67945 -0.3048)
			(end -0.67945 0.3048)
			(stroke
				(width 0.1)
				(type default)
			)
			(layer "B.Fab")
		)
		(fp_line
			(start 0.12065 -0.2794)
			(end -0.12065 -0.2794)
			(stroke
				(width 0.1)
				(type default)
			)
			(layer "B.Fab")
		)
		(fp_line
			(start -0.12065 -0.2794)
			(end -0.12065 -0.3048)
			(stroke
				(width 0.1)
				(type default)
			)
			(layer "B.Fab")
		)
		(fp_line
			(start 0.12065 0.2794)
			(end 0.12065 0.3048)
			(stroke
				(width 0.1)
				(type default)
			)
			(layer "B.Fab")
		)
		(fp_line
			(start -0.120396 0.2794)
			(end 0.12065 0.2794)
			(stroke
				(width 0.1)
				(type default)
			)
			(layer "B.Fab")
		)
		(fp_line
			(start 0.67945 0.3048)
			(end 0.67945 -0.305054)
			(stroke
				(width 0.1)
				(type default)
			)
			(layer "B.Fab")
		)
		(fp_line
			(start 0.12065 0.3048)
			(end 0.67945 0.3048)
			(stroke
				(width 0.1)
				(type default)
			)
			(layer "B.Fab")
		)
		(fp_line
			(start -0.120396 0.3048)
			(end -0.120396 0.2794)
			(stroke
				(width 0.1)
				(type default)
			)
			(layer "B.Fab")
		)
		(fp_line
			(start -0.67945 0.3048)
			(end -0.120396 0.3048)
			(stroke
				(width 0.1)
				(type default)
			)
			(layer "B.Fab")
		)
		(pad "1" smd circle
			(at 0.40005 0 270)
			(size 0 0)
			(layers "B.Cu" "B.Mask" "B.Paste")
			(net "I3C_SPD_DDRABCD_CPU1_LVC1_SCL_3")
		)
		(pad "2" smd circle
			(at -0.40005 0 270)
			(size 0 0)
			(layers "B.Cu" "B.Mask" "B.Paste")
			(net "I3C_SPD_DDRABCD_CPU1_LVC1_SCL")
		)
	)
	(footprint ""
		(layer "B.Cu")
		(at 454.74128 -76.589128 -90)
		(property "Reference" "PC2344"
			(at 0 0 90)
			(layer "B.SilkS")
			(hide yes)
			(effects
				(font
					(size 1.27 1.27)
				)
				(justify mirror)
			)
		)
		(property "Value" ""
			(at 0 0 90)
			(layer "B.Fab")
			(effects
				(font
					(size 1.27 1.27)
				)
				(justify mirror)
			)
		)
		(duplicate_pad_numbers_are_jumpers no)
		(fp_line
			(start -1.524 0.762)
			(end 1.524 0.762)
			(stroke
				(width 0.1524)
				(type default)
			)
			(layer "B.SilkS")
		)
		(fp_line
			(start 1.524 0.762)
			(end 1.524 -0.762)
			(stroke
				(width 0.1524)
				(type default)
			)
			(layer "B.SilkS")
		)
		(fp_line
			(start -1.524 -0.762)
			(end -1.524 0.762)
			(stroke
				(width 0.1524)
				(type default)
			)
			(layer "B.SilkS")
		)
		(fp_line
			(start 1.524 -0.762)
			(end -1.524 -0.762)
			(stroke
				(width 0.1524)
				(type default)
			)
			(layer "B.SilkS")
		)
		(fp_line
			(start -1.1049 0.724916)
			(end -1.1049 -0.724916)
			(stroke
				(width 0.1)
				(type default)
			)
			(layer "B.Fab")
		)
		(fp_line
			(start 1.1049 0.724916)
			(end -1.1049 0.724916)
			(stroke
				(width 0.1)
				(type default)
			)
			(layer "B.Fab")
		)
		(fp_line
			(start -1.1049 -0.724916)
			(end 1.1049 -0.724916)
			(stroke
				(width 0.1)
				(type default)
			)
			(layer "B.Fab")
		)
		(fp_line
			(start 1.1049 -0.724916)
			(end 1.1049 0.724916)
			(stroke
				(width 0.1)
				(type default)
			)
			(layer "B.Fab")
		)
		(pad "1" smd rect
			(at 0.889 0 270)
			(size 1.016 1.27)
			(layers "B.Cu" "B.Mask" "B.Paste")
			(net "SW_P3V3_AUX_FLT")
		)
		(pad "2" smd rect
			(at -0.889 0 270)
			(size 1.016 1.27)
			(layers "B.Cu" "B.Mask" "B.Paste")
			(net "GND")
		)
	)
	(footprint ""
		(layer "B.Cu")
		(at 181.875938 -104.716326 180)
		(property "Reference" "R1328"
			(at 0 0 0)
			(layer "B.SilkS")
			(hide yes)
			(effects
				(font
					(size 1.27 1.27)
				)
				(justify mirror)
			)
		)
		(property "Value" ""
			(at 0 0 0)
			(layer "B.Fab")
			(effects
				(font
					(size 1.27 1.27)
				)
				(justify mirror)
			)
		)
		(duplicate_pad_numbers_are_jumpers no)
		(fp_line
			(start 0.7874 0.4064)
			(end 0.7874 -0.4064)
			(stroke
				(width 0.1524)
				(type default)
			)
			(layer "B.SilkS")
		)
		(fp_line
			(start 0.7874 -0.4064)
			(end -0.7874 -0.4064)
			(stroke
				(width 0.1524)
				(type default)
			)
			(layer "B.SilkS")
		)
		(fp_line
			(start -0.7874 0.4064)
			(end 0.7874 0.4064)
			(stroke
				(width 0.1524)
				(type default)
			)
			(layer "B.SilkS")
		)
		(fp_line
			(start -0.7874 -0.4064)
			(end -0.7874 0.4064)
			(stroke
				(width 0.1524)
				(type default)
			)
			(layer "B.SilkS")
		)
		(fp_line
			(start 0.67945 0.3048)
			(end 0.67945 -0.305054)
			(stroke
				(width 0.1)
				(type default)
			)
			(layer "B.Fab")
		)
		(fp_line
			(start 0.67945 -0.305054)
			(end 0.12065 -0.305054)
			(stroke
				(width 0.1)
				(type default)
			)
			(layer "B.Fab")
		)
		(fp_line
			(start 0.12065 0.3048)
			(end 0.67945 0.3048)
			(stroke
				(width 0.1)
				(type default)
			)
			(layer "B.Fab")
		)
		(fp_line
			(start 0.12065 0.2794)
			(end 0.12065 0.3048)
			(stroke
				(width 0.1)
				(type default)
			)
			(layer "B.Fab")
		)
		(fp_line
			(start 0.12065 -0.2794)
			(end -0.12065 -0.2794)
			(stroke
				(width 0.1)
				(type default)
			)
			(layer "B.Fab")
		)
		(fp_line
			(start 0.12065 -0.305054)
			(end 0.12065 -0.2794)
			(stroke
				(width 0.1)
				(type default)
			)
			(layer "B.Fab")
		)
		(fp_line
			(start -0.120396 0.3048)
			(end -0.120396 0.2794)
			(stroke
				(width 0.1)
				(type default)
			)
			(layer "B.Fab")
		)
		(fp_line
			(start -0.120396 0.2794)
			(end 0.12065 0.2794)
			(stroke
				(width 0.1)
				(type default)
			)
			(layer "B.Fab")
		)
		(fp_line
			(start -0.12065 -0.2794)
			(end -0.12065 -0.3048)
			(stroke
				(width 0.1)
				(type default)
			)
			(layer "B.Fab")
		)
		(fp_line
			(start -0.12065 -0.3048)
			(end -0.67945 -0.3048)
			(stroke
				(width 0.1)
				(type default)
			)
			(layer "B.Fab")
		)
		(fp_line
			(start -0.67945 0.3048)
			(end -0.120396 0.3048)
			(stroke
				(width 0.1)
				(type default)
			)
			(layer "B.Fab")
		)
		(fp_line
			(start -0.67945 -0.3048)
			(end -0.67945 0.3048)
			(stroke
				(width 0.1)
				(type default)
			)
			(layer "B.Fab")
		)
		(pad "1" smd circle
			(at 0.40005 0)
			(size 0 0)
			(layers "B.Cu" "B.Mask" "B.Paste")
			(net "PWRGD_DRAMPWRGD_CPU0_GH_R_LVC1")
		)
		(pad "2" smd circle
			(at -0.40005 0)
			(size 0 0)
			(layers "B.Cu" "B.Mask" "B.Paste")
			(net "GND")
		)
	)
)
